# T6G (Grand Teton) — schematic netlist excerpt (pin names and nets, part order shuffled) for the footprints in the layout excerpt that follows; sources: Cadence DE-HDL packaged netlist, KiCad conversion of 04192023_DAF0TMB3IC0_F0TG_MB_C_brd_V02_OCP.brd

C296  Q_CAP  10PF 50V 5% EMPTY  pkg 0402  page 210 : A = SVID_PVDDCR_CPU0_P1_SVD_R ; B = GND
C6068  Q_CAP  0.01UF 50V 10% X7R  pkg C0402  page 177 : A = P1V2_AUX ; B = GND

(kicad_pcb
	(version 20260206)
	(generator "pcbnew")
	(generator_version "10.0")
	(general
		(thickness 1.6)
		(legacy_teardrops no)
	)
	(paper "A4")
	(title_block
		(title "04192023_DAF0TMB3IC0_F0TG_MB_C_brd_V02_OCP.brd")
		(comment 1 "Grand Teton / footprints 6917-6918 of 8354")
	)
	(layers
		(0 "F.Cu" signal "TOP")
		(4 "In1.Cu" signal "GND")
		(6 "In2.Cu" signal "IN1")
		(8 "In3.Cu" signal "GND1")
		(10 "In4.Cu" signal "IN2")
		(12 "In5.Cu" signal "GND2")
		(14 "In6.Cu" signal "IN3")
		(16 "In7.Cu" signal "GND3")
		(18 "In8.Cu" signal "VCC")
		(20 "In9.Cu" signal "VCC1")
		(22 "In10.Cu" signal "GND4")
		(24 "In11.Cu" signal "IN4")
		(26 "In12.Cu" signal "GND5")
		(28 "In13.Cu" signal "IN5")
		(30 "In14.Cu" signal "GND6")
		(32 "In15.Cu" signal "IN6")
		(34 "In16.Cu" signal "GND7")
		(2 "B.Cu" signal "BOTTOM")
		(9 "F.Adhes" user "F.Adhesive")
		(11 "B.Adhes" user "B.Adhesive")
		(13 "F.Paste" user "Package Geometry/Pastemask Top")
		(15 "B.Paste" user "Package Geometry/Pastemask Bottom")
		(5 "F.SilkS" user "Ref Des/Silkscreen Top")
		(7 "B.SilkS" user "Ref Des/Silkscreen Bottom")
		(1 "F.Mask" user "Board Geometry/Soldermask Top")
		(3 "B.Mask" user "Board Geometry/Soldermask Bottom")
		(17 "Dwgs.User" user "User.Drawings")
		(19 "Cmts.User" user "User.Comments")
		(21 "Eco1.User" user "User.Eco1")
		(23 "Eco2.User" user "User.Eco2")
		(25 "Edge.Cuts" user "Board Geometry/Outline")
		(27 "Margin" user)
		(31 "F.CrtYd" user "Package Geometry/Place Bound Top")
		(29 "B.CrtYd" user "Package Geometry/Place Bound Bottom")
		(35 "F.Fab" user "Ref Des/Assembly Top")
		(33 "B.Fab" user "Ref Des/Assembly Bottom")
	)
	(footprint ""
		(layer "B.Cu")
		(at 85.852 -146.939)
		(property "Reference" "C296"
			(at 0 0 0)
			(layer "B.SilkS")
			(hide yes)
			(effects
				(font
					(size 1.27 1.27)
				)
				(justify mirror)
			)
		)
		(property "Value" ""
			(at 0 0 0)
			(layer "B.Fab")
			(effects
				(font
					(size 1.27 1.27)
				)
				(justify mirror)
			)
		)
		(duplicate_pad_numbers_are_jumpers no)
		(fp_line
			(start -0.7874 -0.4064)
			(end -0.7874 0.4064)
			(stroke
				(width 0.1524)
				(type default)
			)
			(layer "B.SilkS")
		)
		(fp_line
			(start -0.7874 0.4064)
			(end 0.7874 0.4064)
			(stroke
				(width 0.1524)
				(type default)
			)
			(layer "B.SilkS")
		)
		(fp_line
			(start 0.7874 -0.4064)
			(end -0.7874 -0.4064)
			(stroke
				(width 0.1524)
				(type default)
			)
			(layer "B.SilkS")
		)
		(fp_line
			(start 0.7874 0.4064)
			(end 0.7874 -0.4064)
			(stroke
				(width 0.1524)
				(type default)
			)
			(layer "B.SilkS")
		)
		(fp_line
			(start -0.67945 -0.3048)
			(end -0.67945 0.3048)
			(stroke
				(width 0.1)
				(type default)
			)
			(layer "B.Fab")
		)
		(fp_line
			(start -0.67945 0.3048)
			(end -0.120396 0.3048)
			(stroke
				(width 0.1)
				(type default)
			)
			(layer "B.Fab")
		)
		(fp_line
			(start -0.12065 -0.3048)
			(end -0.67945 -0.3048)
			(stroke
				(width 0.1)
				(type default)
			)
			(layer "B.Fab")
		)
		(fp_line
			(start -0.12065 -0.2794)
			(end -0.12065 -0.3048)
			(stroke
				(width 0.1)
				(type default)
			)
			(layer "B.Fab")
		)
		(fp_line
			(start -0.120396 0.2794)
			(end 0.12065 0.2794)
			(stroke
				(width 0.1)
				(type default)
			)
			(layer "B.Fab")
		)
		(fp_line
			(start -0.120396 0.3048)
			(end -0.120396 0.2794)
			(stroke
				(width 0.1)
				(type default)
			)
			(layer "B.Fab")
		)
		(fp_line
			(start 0.12065 -0.305054)
			(end 0.12065 -0.2794)
			(stroke
				(width 0.1)
				(type default)
			)
			(layer "B.Fab")
		)
		(fp_line
			(start 0.12065 -0.2794)
			(end -0.12065 -0.2794)
			(stroke
				(width 0.1)
				(type default)
			)
			(layer "B.Fab")
		)
		(fp_line
			(start 0.12065 0.2794)
			(end 0.12065 0.3048)
			(stroke
				(width 0.1)
				(type default)
			)
			(layer "B.Fab")
		)
		(fp_line
			(start 0.12065 0.3048)
			(end 0.67945 0.3048)
			(stroke
				(width 0.1)
				(type default)
			)
			(layer "B.Fab")
		)
		(fp_line
			(start 0.67945 -0.305054)
			(end 0.12065 -0.305054)
			(stroke
				(width 0.1)
				(type default)
			)
			(layer "B.Fab")
		)
		(fp_line
			(start 0.67945 0.3048)
			(end 0.67945 -0.305054)
			(stroke
				(width 0.1)
				(type default)
			)
			(layer "B.Fab")
		)
		(pad "1" smd circle
			(at 0.40005 0 180)
			(size 0 0)
			(layers "B.Cu" "B.Mask" "B.Paste")
			(net "SVID_PVDDCR_CPU0_P1_SVD_R")
		)
		(pad "2" smd circle
			(at -0.40005 0 180)
			(size 0 0)
			(layers "B.Cu" "B.Mask" "B.Paste")
			(net "GND")
		)
	)
	(footprint ""
		(layer "B.Cu")
		(at 136.040114 -38.914578)
		(property "Reference" "C6068"
			(at 0 0 0)
			(layer "B.SilkS")
			(hide yes)
			(effects
				(font
					(size 1.27 1.27)
				)
				(justify mirror)
			)
		)
		(property "Value" ""
			(at 0 0 0)
			(layer "B.Fab")
			(effects
				(font
					(size 1.27 1.27)
				)
				(justify mirror)
			)
		)
		(duplicate_pad_numbers_are_jumpers no)
		(fp_line
			(start -0.7874 -0.4064)
			(end -0.7874 0.4064)
			(stroke
				(width 0.1524)
				(type default)
			)
			(layer "B.SilkS")
		)
		(fp_line
			(start -0.7874 0.4064)
			(end 0.7874 0.4064)
			(stroke
				(width 0.1524)
				(type default)
			)
			(layer "B.SilkS")
		)
		(fp_line
			(start 0.7874 -0.4064)
			(end -0.7874 -0.4064)
			(stroke
				(width 0.1524)
				(type default)
			)
			(layer "B.SilkS")
		)
		(fp_line
			(start 0.7874 0.4064)
			(end 0.7874 -0.4064)
			(stroke
				(width 0.1524)
				(type default)
			)
			(layer "B.SilkS")
		)
		(fp_line
			(start -0.67945 -0.3048)
			(end -0.67945 0.3048)
			(stroke
				(width 0.1)
				(type default)
			)
			(layer "B.Fab")
		)
		(fp_line
			(start -0.67945 0.3048)
			(end -0.120396 0.3048)
			(stroke
				(width 0.1)
				(type default)
			)
			(layer "B.Fab")
		)
		(fp_line
			(start -0.12065 -0.3048)
			(end -0.67945 -0.3048)
			(stroke
				(width 0.1)
				(type default)
			)
			(layer "B.Fab")
		)
		(fp_line
			(start -0.12065 -0.2794)
			(end -0.12065 -0.3048)
			(stroke
				(width 0.1)
				(type default)
			)
			(layer "B.Fab")
		)
		(fp_line
			(start -0.120396 0.2794)
			(end 0.12065 0.2794)
			(stroke
				(width 0.1)
				(type default)
			)
			(layer "B.Fab")
		)
		(fp_line
			(start -0.120396 0.3048)
			(end -0.120396 0.2794)
			(stroke
				(width 0.1)
				(type default)
			)
			(layer "B.Fab")
		)
		(fp_line
			(start 0.12065 -0.305054)
			(end 0.12065 -0.2794)
			(stroke
				(width 0.1)
				(type default)
			)
			(layer "B.Fab")
		)
		(fp_line
			(start 0.12065 -0.2794)
			(end -0.12065 -0.2794)
			(stroke
				(width 0.1)
				(type default)
			)
			(layer "B.Fab")
		)
		(fp_line
			(start 0.12065 0.2794)
			(end 0.12065 0.3048)
			(stroke
				(width 0.1)
				(type default)
			)
			(layer "B.Fab")
		)
		(fp_line
			(start 0.12065 0.3048)
			(end 0.67945 0.3048)
			(stroke
				(width 0.1)
				(type default)
			)
			(layer "B.Fab")
		)
		(fp_line
			(start 0.67945 -0.305054)
			(end 0.12065 -0.305054)
			(stroke
				(width 0.1)
				(type default)
			)
			(layer "B.Fab")
		)
		(fp_line
			(start 0.67945 0.3048)
			(end 0.67945 -0.305054)
			(stroke
				(width 0.1)
				(type default)
			)
			(layer "B.Fab")
		)
		(pad "1" smd circle
			(at 0.40005 0 180)
			(size 0 0)
			(layers "B.Cu" "B.Mask" "B.Paste")
			(net "P1V2_AUX")
		)
		(pad "2" smd circle
			(at -0.40005 0 180)
			(size 0 0)
			(layers "B.Cu" "B.Mask" "B.Paste")
			(net "GND")
		)
	)
)
